# S9S_MB_2U (Grand Teton) — schematic netlist excerpt (pin names and nets, part order shuffled) for the footprints in the layout excerpt that follows; sources: Cadence DE-HDL packaged netlist, KiCad conversion of 03242023_DA0F0TMBIJ0_F0T_Motherboard_J_brd_V01_OCP.brd

R3324  Q_RES  33.2 1% CHIP  pkg 0402LF  page 213 : A = GPU_FPGA_READY_ISO ; B = GPU_FPGA_READY_ISO_R
PR1709  Q_RES  8.87K 1% EMPTY  pkg 0402LF  page 276 : A = PVCCFA_EHV_CPU0_LSET1 ; B = GND

(kicad_pcb
	(version 20260206)
	(generator "pcbnew")
	(generator_version "10.0")
	(general
		(thickness 1.6)
		(legacy_teardrops no)
	)
	(paper "A4")
	(title_block
		(title "03242023_DA0F0TMBIJ0_F0T_Motherboard_J_brd_V01_OCP.brd")
		(comment 1 "Grand Teton / footprints 1908-1909 of 6105")
	)
	(layers
		(0 "F.Cu" signal "TOP")
		(4 "In1.Cu" signal "GND")
		(6 "In2.Cu" signal "IN1")
		(8 "In3.Cu" signal "GND1")
		(10 "In4.Cu" signal "IN2")
		(12 "In5.Cu" signal "GND2")
		(14 "In6.Cu" signal "IN3")
		(16 "In7.Cu" signal "GND3")
		(18 "In8.Cu" signal "VCC")
		(20 "In9.Cu" signal "VCC1")
		(22 "In10.Cu" signal "GND4")
		(24 "In11.Cu" signal "IN4")
		(26 "In12.Cu" signal "GND5")
		(28 "In13.Cu" signal "IN5")
		(30 "In14.Cu" signal "GND6")
		(32 "In15.Cu" signal "IN6")
		(34 "In16.Cu" signal "GND7")
		(2 "B.Cu" signal "BOTTOM")
		(9 "F.Adhes" user "F.Adhesive")
		(11 "B.Adhes" user "B.Adhesive")
		(13 "F.Paste" user "Package Geometry/Pastemask Top")
		(15 "B.Paste" user "Package Geometry/Pastemask Bottom")
		(5 "F.SilkS" user "Ref Des/Silkscreen Top")
		(7 "B.SilkS" user "Ref Des/Silkscreen Bottom")
		(1 "F.Mask" user "Board Geometry/Soldermask Top")
		(3 "B.Mask" user "Board Geometry/Soldermask Bottom")
		(17 "Dwgs.User" user "User.Drawings")
		(19 "Cmts.User" user "User.Comments")
		(21 "Eco1.User" user "User.Eco1")
		(23 "Eco2.User" user "User.Eco2")
		(25 "Edge.Cuts" user "Board Geometry/Outline")
		(27 "Margin" user)
		(31 "F.CrtYd" user "Package Geometry/Place Bound Top")
		(29 "B.CrtYd" user "Package Geometry/Place Bound Bottom")
		(35 "F.Fab" user "Ref Des/Assembly Top")
		(33 "B.Fab" user "Ref Des/Assembly Bottom")
	)
	(footprint ""
		(layer "F.Cu")
		(at 417.558728 -156.17063 180)
		(property "Reference" "PR1709"
			(at 0 0 180)
			(layer "F.SilkS")
			(hide yes)
			(effects
				(font
					(size 1.27 1.27)
				)
			)
		)
		(property "Value" ""
			(at 0 0 180)
			(layer "F.Fab")
			(effects
				(font
					(size 1.27 1.27)
				)
			)
		)
		(duplicate_pad_numbers_are_jumpers no)
		(fp_line
			(start 0.7874 0.4064)
			(end -0.7874 0.4064)
			(stroke
				(width 0.1524)
				(type default)
			)
			(layer "F.SilkS")
		)
		(fp_line
			(start 0.7874 -0.4064)
			(end 0.7874 0.4064)
			(stroke
				(width 0.1524)
				(type default)
			)
			(layer "F.SilkS")
		)
		(fp_line
			(start -0.7874 0.4064)
			(end -0.7874 -0.4064)
			(stroke
				(width 0.1524)
				(type default)
			)
			(layer "F.SilkS")
		)
		(fp_line
			(start -0.7874 -0.4064)
			(end 0.7874 -0.4064)
			(stroke
				(width 0.1524)
				(type default)
			)
			(layer "F.SilkS")
		)
		(fp_line
			(start 0.67945 0.3048)
			(end 0.120396 0.3048)
			(stroke
				(width 0.1)
				(type default)
			)
			(layer "F.Fab")
		)
		(fp_line
			(start 0.67945 -0.3048)
			(end 0.67945 0.3048)
			(stroke
				(width 0.1)
				(type default)
			)
			(layer "F.Fab")
		)
		(fp_line
			(start 0.12065 -0.2794)
			(end 0.12065 -0.3048)
			(stroke
				(width 0.1)
				(type default)
			)
			(layer "F.Fab")
		)
		(fp_line
			(start 0.12065 -0.3048)
			(end 0.67945 -0.3048)
			(stroke
				(width 0.1)
				(type default)
			)
			(layer "F.Fab")
		)
		(fp_line
			(start 0.120396 0.3048)
			(end 0.120396 0.2794)
			(stroke
				(width 0.1)
				(type default)
			)
			(layer "F.Fab")
		)
		(fp_line
			(start 0.120396 0.2794)
			(end -0.12065 0.2794)
			(stroke
				(width 0.1)
				(type default)
			)
			(layer "F.Fab")
		)
		(fp_line
			(start -0.12065 0.3048)
			(end -0.67945 0.3048)
			(stroke
				(width 0.1)
				(type default)
			)
			(layer "F.Fab")
		)
		(fp_line
			(start -0.12065 0.2794)
			(end -0.12065 0.3048)
			(stroke
				(width 0.1)
				(type default)
			)
			(layer "F.Fab")
		)
		(fp_line
			(start -0.12065 -0.2794)
			(end 0.12065 -0.2794)
			(stroke
				(width 0.1)
				(type default)
			)
			(layer "F.Fab")
		)
		(fp_line
			(start -0.12065 -0.305054)
			(end -0.12065 -0.2794)
			(stroke
				(width 0.1)
				(type default)
			)
			(layer "F.Fab")
		)
		(fp_line
			(start -0.67945 0.3048)
			(end -0.67945 -0.305054)
			(stroke
				(width 0.1)
				(type default)
			)
			(layer "F.Fab")
		)
		(fp_line
			(start -0.67945 -0.305054)
			(end -0.12065 -0.305054)
			(stroke
				(width 0.1)
				(type default)
			)
			(layer "F.Fab")
		)
		(pad "1" smd circle
			(at -0.40005 0 180)
			(size 0 0)
			(layers "F.Cu" "F.Mask" "F.Paste")
			(net "PVCCFA_EHV_CPU0_LSET1")
		)
		(pad "2" smd circle
			(at 0.40005 0 180)
			(size 0 0)
			(layers "F.Cu" "F.Mask" "F.Paste")
			(net "GND")
		)
	)
	(footprint ""
		(layer "F.Cu")
		(at 164.64788 -118.836948)
		(property "Reference" "R3324"
			(at 0 0 0)
			(layer "F.SilkS")
			(hide yes)
			(effects
				(font
					(size 1.27 1.27)
				)
			)
		)
		(property "Value" ""
			(at 0 0 0)
			(layer "F.Fab")
			(effects
				(font
					(size 1.27 1.27)
				)
			)
		)
		(duplicate_pad_numbers_are_jumpers no)
		(fp_line
			(start -0.7874 -0.4064)
			(end 0.7874 -0.4064)
			(stroke
				(width 0.1524)
				(type default)
			)
			(layer "F.SilkS")
		)
		(fp_line
			(start -0.7874 0.4064)
			(end -0.7874 -0.4064)
			(stroke
				(width 0.1524)
				(type default)
			)
			(layer "F.SilkS")
		)
		(fp_line
			(start 0.7874 -0.4064)
			(end 0.7874 0.4064)
			(stroke
				(width 0.1524)
				(type default)
			)
			(layer "F.SilkS")
		)
		(fp_line
			(start 0.7874 0.4064)
			(end -0.7874 0.4064)
			(stroke
				(width 0.1524)
				(type default)
			)
			(layer "F.SilkS")
		)
		(fp_line
			(start -0.67945 -0.305054)
			(end -0.12065 -0.305054)
			(stroke
				(width 0.1)
				(type default)
			)
			(layer "F.Fab")
		)
		(fp_line
			(start -0.67945 0.3048)
			(end -0.67945 -0.305054)
			(stroke
				(width 0.1)
				(type default)
			)
			(layer "F.Fab")
		)
		(fp_line
			(start -0.12065 -0.305054)
			(end -0.12065 -0.2794)
			(stroke
				(width 0.1)
				(type default)
			)
			(layer "F.Fab")
		)
		(fp_line
			(start -0.12065 -0.2794)
			(end 0.12065 -0.2794)
			(stroke
				(width 0.1)
				(type default)
			)
			(layer "F.Fab")
		)
		(fp_line
			(start -0.12065 0.2794)
			(end -0.12065 0.3048)
			(stroke
				(width 0.1)
				(type default)
			)
			(layer "F.Fab")
		)
		(fp_line
			(start -0.12065 0.3048)
			(end -0.67945 0.3048)
			(stroke
				(width 0.1)
				(type default)
			)
			(layer "F.Fab")
		)
		(fp_line
			(start 0.120396 0.2794)
			(end -0.12065 0.2794)
			(stroke
				(width 0.1)
				(type default)
			)
			(layer "F.Fab")
		)
		(fp_line
			(start 0.120396 0.3048)
			(end 0.120396 0.2794)
			(stroke
				(width 0.1)
				(type default)
			)
			(layer "F.Fab")
		)
		(fp_line
			(start 0.12065 -0.3048)
			(end 0.67945 -0.3048)
			(stroke
				(width 0.1)
				(type default)
			)
			(layer "F.Fab")
		)
		(fp_line
			(start 0.12065 -0.2794)
			(end 0.12065 -0.3048)
			(stroke
				(width 0.1)
				(type default)
			)
			(layer "F.Fab")
		)
		(fp_line
			(start 0.67945 -0.3048)
			(end 0.67945 0.3048)
			(stroke
				(width 0.1)
				(type default)
			)
			(layer "F.Fab")
		)
		(fp_line
			(start 0.67945 0.3048)
			(end 0.120396 0.3048)
			(stroke
				(width 0.1)
				(type default)
			)
			(layer "F.Fab")
		)
		(pad "1" smd circle
			(at -0.40005 0)
			(size 0 0)
			(layers "F.Cu" "F.Mask" "F.Paste")
			(net "GPU_FPGA_READY_ISO")
		)
		(pad "2" smd circle
			(at 0.40005 0)
			(size 0 0)
			(layers "F.Cu" "F.Mask" "F.Paste")
			(net "GPU_FPGA_READY_ISO_R")
		)
	)
)
